FILE_TYPE = CONNECTIVITY;
{Allegro Design Entry HDL 17.2-2016 S081 (4005846) 1/11/2022}
"PAGE_NUMBER" = 197;
0"NC";
1"GND\g";
2"GND\g";
3"GND\g";
4"GND\g";
5"GND\g";
6"GND\g";
7"GND\g";
8"GND\g";
9"GND\g";
10"GND\g";
11"P12V_STBY\g";
12"PVDDCR_CPU1_P1_VCCS"CDS_PHYS_NET_NAME"PVCCIN_CPU0_VREF";
13"SW_PVDDIO_P1_BOOTR1";
14"SW_PVDDIO_P1_SW1";
15"SW_PVDDIO_P1_BOOTR2";
16"SW_PVDDIO_P1_SW2";
17"GND\g";
18"GND\g";
19"PVDDIO_P1\g";
20"PVDDIO_P1\g";
21"PVDDIO_P1\g";
22"GND\g";
23"IND_PVDDIO_P1_CPL2";
24"SW_PVDDIO_P1_BOOT2_R";
25"IND_PVDDIO_P1_CPL3";
26"SW_PVDDIO_P1_SW1_RC";
27"GND\g";
28"PVDDIO_P1_VOS1";
29"SW_PVDDIO_P1_BOOT1";
30"NC_PVDDIO_P1_GL2_1";
31"NC_PVDDIO_P1_GL1_1";
32"PVDDIO_P1_IMON1";
33"PVDDIO_P1_PWM1";
34"PVDDIO_P1_TEMP1";
35"NC_PVDDIO_P1_DNC1";
36"PVDDIO_P1_LSET1"CDS_PHYS_NET_NAME"PVCCFA_EHV_FIVRA_CPU0_LSET1";
37"PVDDIO_P1_VCC1"CDS_PHYS_NET_NAME"PVCCFA_EHV_FIVRA_CPU0_VDD1";
38"PVDDCR_CPU1_P1_PVCC\g";
39"GND\g";
40"SW_PVDDIO_P1_BOOT2";
41"NC_PVDDIO_P1_GL1_2";
42"PVDDIO_P1_IMON2";
43"NC_PVDDIO_P1_DNC2";
44"PVDDIO_P1_VCC2"CDS_PHYS_NET_NAME"PVCCFA_EHV_FIVRA_CPU0_VDD2";
45"PVDDCR_CPU1_P1_PVCC\g";
46"PVDDCR_CPU1_P1_VCCS"CDS_PHYS_NET_NAME"PVCCIN_CPU0_VREF";
47"IND_PVDDIO_P1_CPL2";
48"GND\g";
49"SW_P12V_STBY_PVDDIO_P1_FLT\g";
50"SW_PVDDIO_P1_BOOT1_R";
51"GND\g";
52"SW_PVDDIO_P1_SW2_RC";
53"NC_PVDDIO_P1_GL2_2";
54"PVDDIO_P1_VOS2";
55"SW_P12V_STBY_PVDDIO_P1_FLT\g";
56"GND\g";
57"PVDDIO_P1_PWM2";
58"PVDDIO_P1_TEMP1";
59"PVDDIO_P1_LSET2";
%"UNIVERSAL_GND"
"1","(550,1325)","0","pure_quanta_power","I1";
;
CDS_LIB"pure_quanta_power"
HDL_POWER"GND";
"A"1;
%"VCC_CORE"
"1","(4575,6050)","0","pure_quanta_power","I100";
;
HDL_POWER"SW_P12V_STBY_PVDDIO_P1_FLT"
CDS_LIB"pure_quanta_power";
"A"49;
%"VCC_CORE"
"1","(5175,3350)","0","pure_quanta_power","I101";
;
HDL_POWER"SW_P12V_STBY_PVDDIO_P1_FLT"
CDS_LIB"pure_quanta_power";
"A"55;
%"Q_CAP"
"1","(25,4425)","0","pure_quanta","I105";
;
LOCATION"PC435_7"
$SEC"1"
CDS_SEC"1"
MATERIAL"X7R"
TOLERANCE"10%"
VALUE"0.1UF"
PART_NUMBER"CH4104K1B00"
VOLTAGE"25V"
PACK_TYPE"0402"
CDS_LIB"pure_quanta";
"B"
$PN"2"7;
"A"
$PN"1"12;
%"Q_CAP"
"1","(25,1675)","0","pure_quanta","I106";
;
LOCATION"PC436_8"
$SEC"1"
CDS_SEC"1"
VALUE"0.1UF"
VOLTAGE"25V"
TOLERANCE"10%"
MATERIAL"X7R"
PART_NUMBER"CH4104K1B00"
PACK_TYPE"0402"
CDS_LIB"pure_quanta";
"B"
$PN"2"8;
"A"
$PN"1"46;
%"Q_RES"
"1","(4925,1025)","0","pure_quanta","I107";
;
LOCATION"PR281"
$SEC"1"
CDS_SEC"1"
WATTAGE"1/16W"
MATERIAL"CHIP"
TOLERANCE"5%"
VALUE"0"
PART_NUMBER"CS00002JB38"
PACK_TYPE"0402LF"
CDS_LIB"pure_quanta";
"B"
$PN"2"21;
"A"
$PN"1"54;
%"Q_RES"
"1","(5100,3800)","0","pure_quanta","I108";
;
LOCATION"PR280"
$SEC"1"
CDS_SEC"1"
TOLERANCE"5%"
VALUE"0"
WATTAGE"1/16W"
MATERIAL"CHIP"
PART_NUMBER"CS00002JB38"
PACK_TYPE"0402LF"
CDS_LIB"pure_quanta";
"B"
$PN"2"19;
"A"
$PN"1"28;
%"Q_CAP"
"1","(4925,5025)","0","pure_quanta","I109";
;
LOCATION"PC447"
$SEC"1"
CDS_SEC"1"
PART_NUMBER"CH4223K1B00"
MATERIAL"X7R"
TOLERANCE"10%"
VALUE"0.22UF"
VOLTAGE"16V"
PACK_TYPE"0402"
CDS_LIB"pure_quanta";
"B"
$PN"2"13;
"A"
$PN"1"50;
%"Q_CAP"
"1","(4575,2275)","0","pure_quanta","I110";
;
LOCATION"PC445"
$SEC"1"
CDS_SEC"1"
MATERIAL"X7R"
TOLERANCE"10%"
VALUE"0.22UF"
PART_NUMBER"CH4223K1B00"
VOLTAGE"16V"
PACK_TYPE"0402"
CDS_LIB"pure_quanta";
"B"
$PN"2"15;
"A"
$PN"1"24;
%"Q_INDUCTOR4P_14"
"1","(5950,1925)","0","pure_quanta","I111";
;
LOCATION"PL48"
$SEC"1"
CDS_SEC"1"
PART_TYPE"SMLF"
MATERIAL"IND"
VALUE"150NH"
PART_NUMBER"CV+15^0TZ04"
CDS_LIB"pure_quanta"
NEEDS_NO_SIZE"TRUE";
"1"
$PN"1"16;
"4"
$PN"4"21;
"3"
$PN"3"23;
"2"
$PN"2"25;
%"Q_INDUCTOR4P_14"
"1","(5775,4675)","0","pure_quanta","I112";
;
LOCATION"PL47"
$SEC"1"
CDS_SEC"1"
MATERIAL"IND"
PART_TYPE"SMLF"
VALUE"150NH"
PART_NUMBER"CV+15^0TZ04"
CDS_LIB"pure_quanta"
NEEDS_NO_SIZE"TRUE";
"1"
$PN"1"14;
"4"
$PN"4"19;
"3"
$PN"3"18;
"2"
$PN"2"47;
%"Q_RES"
"1","(3850,2400)","0","pure_quanta","I113";
;
LOCATION"PR278"
$SEC"1"
CDS_SEC"1"
PACK_TYPE"0402LF"
TOLERANCE"1%"
MATERIAL"CHIP"
WATTAGE"1/16W"
VALUE"4.7"
PART_NUMBER"CS-4702FB19"
CDS_LIB"pure_quanta";
"B"
$PN"2"24;
"A"
$PN"1"40;
%"Q_CAPP"
"1","(5000,5725)","0","pure_quanta","I115";
;
LOCATION"PC454"
$SEC"1"
CDS_SEC"1"
MATERIAL"OSCON"
TOLERANCE"20%"
VALUE"220UF"
PART_NUMBER"SP_CC72204MD02"
VOLTAGE"25V"
PACK_TYPE"THLF"
CDS_LIB"pure_quanta";
"A"
$PN"1"49;
"B"
$PN"2"48;
%"Q_CAPP"
"1","(6925,3075)","0","pure_quanta","I118";
;
LOCATION"PC450"
$SEC"1"
CDS_SEC"1"
PART_NUMBER"CH747LM8825"
MATERIAL"SPCAP"
TOLERANCE"20%"
VALUE"470UF"
VOLTAGE"2.5V"
PACK_TYPE"SMLF"
CDS_LIB"pure_quanta";
"A"
$PN"1"20;
"B"
$PN"2"51;
%"Q_CAP"
"1","(3325,5700)","0","pure_quanta","I119";
;
LOCATION"PC438_1"
$SEC"1"
CDS_SEC"1"
MATERIAL"X7R"
TOLERANCE"10%"
VALUE"0.1UF"
PART_NUMBER"CH4104K1B00"
VOLTAGE"25V"
PACK_TYPE"0402"
CDS_LIB"pure_quanta";
"B"
$PN"2"48;
"A"
$PN"1"49;
%"Q_CAP"
"1","(3400,2975)","0","pure_quanta","I120";
;
LOCATION"PC439_2"
$SEC"1"
CDS_SEC"1"
MATERIAL"X7R"
TOLERANCE"10%"
VALUE"0.1UF"
PART_NUMBER"CH4104K1B00"
VOLTAGE"25V"
PACK_TYPE"0402"
CDS_LIB"pure_quanta";
"B"
$PN"2"39;
"A"
$PN"1"55;
%"Q_CAP"
"1","(1000,5075)","0","pure_quanta","I121";
;
LOCATION"PC433"
$SEC"1"
CDS_SEC"1"
MATERIAL"X6S"
TOLERANCE"10%"
VALUE"2.2UF"
PART_NUMBER"CH5222KEB01"
VOLTAGE"10V"
PACK_TYPE"C0402"
CDS_LIB"pure_quanta";
"B"
$PN"2"2;
"A"
$PN"1"37;
%"UNIVERSAL_GND"
"1","(1000,4875)","0","pure_quanta_power","I122";
;
CDS_LIB"pure_quanta_power"
HDL_POWER"GND";
"A"2;
%"UNIVERSAL_GND"
"1","(1350,5375)","0","pure_quanta_power","I123";
;
CDS_LIB"pure_quanta_power"
HDL_POWER"GND";
"A"3;
%"Q_RES"
"2","(1000,5625)","0","pure_quanta","I124";
;
LOCATION"PR277"
$SEC"1"
CDS_SEC"1"
WATTAGE"1/16W"
MATERIAL"CHIP"
TOLERANCE"1%"
VALUE"2.2"
PART_NUMBER"CS-2202FB00"
PACK_TYPE"0402LF"
CDS_LIB"pure_quanta";
"A"
$PN"1"38;
"B"
$PN"2"37;
%"Q_CAP"
"1","(1350,5650)","0","pure_quanta","I125";
;
LOCATION"PC437_IOP1_1"
$SEC"1"
CDS_SEC"1"
MATERIAL"X6S"
TOLERANCE"10%"
VALUE"2.2UF"
PART_NUMBER"CH5222KEB01"
VOLTAGE"10V"
PACK_TYPE"C0402"
CDS_LIB"pure_quanta";
"B"
$PN"2"3;
"A"
$PN"1"38;
%"Q_CAP"
"1","(900,2450)","0","pure_quanta","I127";
;
LOCATION"PC432"
$SEC"1"
CDS_SEC"1"
MATERIAL"X6S"
PACK_TYPE"C0402"
VOLTAGE"10V"
TOLERANCE"10%"
VALUE"2.2UF"
PART_NUMBER"CH5222KEB01"
CDS_LIB"pure_quanta";
"B"
$PN"2"4;
"A"
$PN"1"44;
%"UNIVERSAL_GND"
"1","(900,2250)","0","pure_quanta_power","I128";
;
CDS_LIB"pure_quanta_power"
HDL_POWER"GND";
"A"4;
%"UNIVERSAL_GND"
"1","(1250,2750)","0","pure_quanta_power","I129";
;
CDS_LIB"pure_quanta_power"
HDL_POWER"GND";
"A"5;
%"UNIVERSAL_GND"
"1","(575,4125)","0","pure_quanta_power","I13";
;
CDS_LIB"pure_quanta_power"
HDL_POWER"GND";
"A"6;
%"Q_RES"
"2","(900,3000)","0","pure_quanta","I130";
;
LOCATION"PR276"
$SEC"1"
CDS_SEC"1"
WATTAGE"1/16W"
MATERIAL"CHIP"
TOLERANCE"1%"
VALUE"2.2"
PART_NUMBER"CS-2202FB00"
PACK_TYPE"0402LF"
CDS_LIB"pure_quanta";
"A"
$PN"1"45;
"B"
$PN"2"44;
%"Q_CAP"
"1","(1250,3025)","0","pure_quanta","I131";
;
LOCATION"PC434_IOP1_2"
$SEC"1"
CDS_SEC"1"
MATERIAL"X6S"
TOLERANCE"10%"
VALUE"2.2UF"
PART_NUMBER"CH5222KEB01"
VOLTAGE"10V"
PACK_TYPE"C0402"
CDS_LIB"pure_quanta";
"B"
$PN"2"5;
"A"
$PN"1"45;
%"UNIVERSAL_GND"
"1","(25,4225)","0","pure_quanta_power","I133";
;
CDS_LIB"pure_quanta_power"
HDL_POWER"GND";
"A"7;
%"UNIVERSAL_GND"
"1","(25,1475)","0","pure_quanta_power","I134";
;
CDS_LIB"pure_quanta_power"
HDL_POWER"GND";
"A"8;
%"UNIVERSAL_GND"
"1","(4050,3875)","0","pure_quanta_power","I136";
;
CDS_LIB"pure_quanta_power"
HDL_POWER"GND";
"A"9;
%"Q_RES"
"2","(4050,4100)","0","pure_quanta","I137";
;
LOCATION"PR488"
$SEC"1"
CDS_SEC"1"
WATTAGE"1/8W"
MATERIAL"EMPTY"
TOLERANCE"1%"
VALUE"1.5"
PART_NUMBER"CS-1504FB00"
PACK_TYPE"0402LF"
CDS_LIB"pure_quanta";
"A"
$PN"1"26;
"B"
$PN"2"9;
%"Q_CAP"
"1","(4050,4600)","0","pure_quanta","I138";
;
LOCATION"PC174"
$SEC"1"
CDS_SEC"1"
MATERIAL"EMPTY"
TOLERANCE"10%"
VALUE"560PF"
PART_NUMBER"CH1566K1B09"
VOLTAGE"50V"
PACK_TYPE"C0402"
CDS_LIB"pure_quanta";
"B"
$PN"2"26;
"A"
$PN"1"14;
%"Q_CAP"
"1","(3950,1850)","0","pure_quanta","I139";
;
LOCATION"PC175"
$SEC"1"
CDS_SEC"1"
PART_NUMBER"CH1566K1B09"
PACK_TYPE"C0402"
MATERIAL"EMPTY"
TOLERANCE"10%"
VALUE"560PF"
VOLTAGE"50V"
CDS_LIB"pure_quanta";
"B"
$PN"2"52;
"A"
$PN"1"16;
%"Q_RES"
"2","(3950,1350)","0","pure_quanta","I140";
;
LOCATION"PR489"
$SEC"1"
CDS_SEC"1"
TOLERANCE"1%"
VALUE"1.5"
WATTAGE"1/8W"
MATERIAL"EMPTY"
PART_NUMBER"CS-1504FB00"
PACK_TYPE"0402LF"
CDS_LIB"pure_quanta";
"A"
$PN"1"52;
"B"
$PN"2"10;
%"UNIVERSAL_GND"
"1","(3950,1125)","0","pure_quanta_power","I141";
;
CDS_LIB"pure_quanta_power"
HDL_POWER"GND";
"A"10;
%"VCC_CORE"
"1","(1000,6025)","0","pure_quanta_power","I142";
;
HDL_POWER"PVDDCR_CPU1_P1_PVCC"
CDS_LIB"pure_quanta_power";
"A"38;
%"VCC_CORE"
"1","(900,3400)","0","pure_quanta_power","I143";
;
HDL_POWER"PVDDCR_CPU1_P1_PVCC"
CDS_LIB"pure_quanta_power";
"A"45;
%"Q_RES"
"2","(8175,4600)","0","pure_quanta","I144";
;
LOCATION"PR378"
$SEC"1"
CDS_SEC"1"
WATTAGE"1/16W"
MATERIAL"CHIP"
TOLERANCE"1%"
VALUE"1K"
PART_NUMBER"TMP_QCS21002FB24"
PACK_TYPE"0402LF"
CDS_LIB"pure_quanta";
"A"
$PN"1"19;
"B"
$PN"2"17;
%"UNIVERSAL_GND"
"1","(6700,4425)","0","pure_quanta_power","I146";
;
CDS_LIB"pure_quanta_power"
HDL_POWER"GND";
"A"18;
%"Q_RES"
"2","(575,4350)","2","pure_quanta","I17";
;
LOCATION"PR275"
$SEC"1"
CDS_SEC"1"
PACK_TYPE"0402LF"
WATTAGE"1/16W"
MATERIAL"EMPTY"
TOLERANCE"1%"
VALUE"8.87K"
PART_NUMBER"CS28872FB01"
CDS_LIB"pure_quanta";
"A"
$PN"1"36;
"B"
$PN"2"6;
%"Q_RES"
"2","(550,1550)","2","pure_quanta","I2";
;
LOCATION"PR274"
$SEC"1"
CDS_SEC"1"
WATTAGE"1/16W"
MATERIAL"EMPTY"
TOLERANCE"1%"
VALUE"8.87K"
PART_NUMBER"CS28872FB01"
PACK_TYPE"0402LF"
CDS_LIB"pure_quanta";
"A"
$PN"1"59;
"B"
$PN"2"1;
%"ISL99390FRZTR5935"
"1","(2575,2050)","0","pure_quanta","I30";
;
LOCATION"PU40"
$SEC"1"
CDS_SEC"1"
PART_TYPE"SMLF"
MATERIAL"IC"
VALUE"ISL99390FRZ-TR5935"
PART_NUMBER"AL099390004"
CDS_LIB"pure_quanta"
CDS_LMAN_SYM_OUTLINE"-300,700,250,-650"
NEEDS_NO_SIZE"TRUE";
"PGND2"
$PN"7_9-20_24"56;
"GL2"
$PN"41"53;
"GL1"
$PN"6"41;
"DNC"
$PN"31"43;
"EN"
$PN"35"44;
"PGND3"
$PN"40"56;
"VOS"
$PN"1"54;
"VIN2"
$PN"30"55;
"PGND1"
$PN"5"56;
"SW"
$PN"10_19"16;
"LSET"
$PN"37"59;
"IOUT"
$PN"38"42;
"TOUT_FLT"
$PN"36"58;
"PVCC"
$PN"4"45;
"PHASE"
$PN"32"15;
"VIN1"
$PN"25_29"55;
"BOOT"
$PN"33"40;
"AGND"
$PN"2"56;
"VCC"
$PN"3"44;
"REFIN"
$PN"39"46;
"PWM"
$PN"34"57;
%"UNIVERSAL_GND"
"1","(3225,1325)","0","pure_quanta_power","I31";
;
CDS_LIB"pure_quanta_power"
HDL_POWER"GND";
"A"56;
%"UNIVERSAL_GND"
"1","(3225,4075)","0","pure_quanta_power","I34";
;
CDS_LIB"pure_quanta_power"
HDL_POWER"GND";
"A"27;
%"ISL99390FRZTR5935"
"1","(2575,4800)","0","pure_quanta","I35";
;
LOCATION"PU39"
$SEC"1"
CDS_SEC"1"
PART_TYPE"SMLF"
MATERIAL"IC"
VALUE"ISL99390FRZ-TR5935"
PART_NUMBER"AL099390004"
NEEDS_NO_SIZE"TRUE"
CDS_LMAN_SYM_OUTLINE"-300,700,250,-650"
CDS_LIB"pure_quanta";
"PGND2"
$PN"7_9-20_24"27;
"GL2"
$PN"41"30;
"GL1"
$PN"6"31;
"DNC"
$PN"31"35;
"EN"
$PN"35"37;
"PGND3"
$PN"40"27;
"VOS"
$PN"1"28;
"VIN2"
$PN"30"49;
"PGND1"
$PN"5"27;
"SW"
$PN"10_19"14;
"LSET"
$PN"37"36;
"IOUT"
$PN"38"32;
"TOUT_FLT"
$PN"36"34;
"PVCC"
$PN"4"38;
"PHASE"
$PN"32"13;
"VIN1"
$PN"25_29"49;
"BOOT"
$PN"33"29;
"AGND"
$PN"2"27;
"VCC"
$PN"3"37;
"REFIN"
$PN"39"12;
"PWM"
$PN"34"33;
%"Q_CAP"
"1","(3900,2975)","0","pure_quanta","I39";
;
LOCATION"PC441_2"
$SEC"1"
CDS_SEC"1"
MATERIAL"X6S"
TOLERANCE"10%"
VALUE"1UF"
PART_NUMBER"CH5104KEB02"
VOLTAGE"25V"
PACK_TYPE"C0402"
CDS_LIB"pure_quanta";
"B"
$PN"2"39;
"A"
$PN"1"55;
%"Q_CAP"
"1","(4300,2975)","0","pure_quanta","I41";
;
LOCATION"PC443_2"
$SEC"1"
CDS_SEC"1"
MATERIAL"X6S"
TOLERANCE"10%"
VALUE"10UF"
PART_NUMBER"CH6104KEA00"
VOLTAGE"25V"
PACK_TYPE"C0805"
CDS_LIB"pure_quanta";
"B"
$PN"2"39;
"A"
$PN"1"55;
%"Q_CAP"
"1","(4700,2975)","0","pure_quanta","I42";
;
LOCATION"PC446_2"
$SEC"1"
CDS_SEC"1"
MATERIAL"X6S"
TOLERANCE"10%"
VALUE"10UF"
PART_NUMBER"CH6104KEA00"
VOLTAGE"25V"
PACK_TYPE"C0805"
CDS_LIB"pure_quanta";
"B"
$PN"2"39;
"A"
$PN"1"55;
%"UNIVERSAL_GND"
"1","(5175,2625)","0","pure_quanta_power","I44";
;
CDS_LIB"pure_quanta_power"
HDL_POWER"GND";
"A"39;
%"Q_CAP"
"1","(3650,5700)","0","pure_quanta","I50";
;
LOCATION"PC440_1"
$SEC"1"
CDS_SEC"1"
MATERIAL"X6S"
TOLERANCE"10%"
VALUE"1UF"
PART_NUMBER"CH5104KEB02"
VOLTAGE"25V"
PACK_TYPE"C0402"
CDS_LIB"pure_quanta";
"B"
$PN"2"48;
"A"
$PN"1"49;
%"Q_RES"
"1","(3900,5150)","0","pure_quanta","I51";
;
LOCATION"PR279"
$SEC"1"
CDS_SEC"1"
PACK_TYPE"0402LF"
TOLERANCE"1%"
MATERIAL"CHIP"
WATTAGE"1/16W"
VALUE"4.7"
PART_NUMBER"CS-4702FB19"
CDS_LIB"pure_quanta";
"B"
$PN"2"50;
"A"
$PN"1"29;
%"Q_CAP"
"1","(3975,5700)","0","pure_quanta","I52";
;
LOCATION"PC442_1"
$SEC"1"
CDS_SEC"1"
MATERIAL"X6S"
TOLERANCE"10%"
VALUE"10UF"
PART_NUMBER"CH6104KEA00"
VOLTAGE"25V"
PACK_TYPE"C0805"
CDS_LIB"pure_quanta";
"B"
$PN"2"48;
"A"
$PN"1"49;
%"Q_CAP"
"1","(4300,5700)","0","pure_quanta","I56";
;
LOCATION"PC444_1"
$SEC"1"
CDS_SEC"1"
MATERIAL"X6S"
TOLERANCE"10%"
VALUE"10UF"
PART_NUMBER"CH6104KEA00"
VOLTAGE"25V"
PACK_TYPE"C0805"
CDS_LIB"pure_quanta";
"B"
$PN"2"48;
"A"
$PN"1"49;
%"UNIVERSAL_GND"
"1","(4575,5325)","0","pure_quanta_power","I57";
;
CDS_LIB"pure_quanta_power"
HDL_POWER"GND";
"A"48;
%"Q_CAP"
"1","(7400,1850)","0","pure_quanta","I60";
;
LOCATION"PC458_2"
$SEC"1"
CDS_SEC"1"
MATERIAL"X6S"
TOLERANCE"20%"
VALUE"22UF"
PART_NUMBER"TMP_QCH622KMEA01"
VOLTAGE"4V"
PACK_TYPE"0805"
CDS_LIB"pure_quanta";
"B"
$PN"2"22;
"A"
$PN"1"21;
%"Q_CAP"
"1","(7825,1850)","0","pure_quanta","I61";
;
LOCATION"PC460_2"
$SEC"1"
CDS_SEC"1"
MATERIAL"X6S"
TOLERANCE"20%"
VALUE"22UF"
PART_NUMBER"TMP_QCH622KMEA01"
VOLTAGE"4V"
PACK_TYPE"0805"
CDS_LIB"pure_quanta";
"B"
$PN"2"22;
"A"
$PN"1"21;
%"VCC_CORE"
"1","(7825,2200)","0","pure_quanta_power","I64";
;
HDL_POWER"PVDDIO_P1"
CDS_LIB"pure_quanta_power";
"A"21;
%"Q_CAPP"
"1","(7325,3075)","0","pure_quanta","I66";
;
LOCATION"PC452"
$SEC"1"
CDS_SEC"1"
MATERIAL"SPCAP"
TOLERANCE"20%"
VALUE"470UF"
PART_NUMBER"CH747LM8825"
VOLTAGE"2.5V"
PACK_TYPE"SMLF"
CDS_LIB"pure_quanta";
"A"
$PN"1"20;
"B"
$PN"2"51;
%"UNIVERSAL_GND"
"1","(7725,2725)","0","pure_quanta_power","I67";
;
CDS_LIB"pure_quanta_power"
HDL_POWER"GND";
"A"51;
%"Q_CAPP"
"1","(7725,3075)","0","pure_quanta","I68";
;
LOCATION"PC455"
$SEC"1"
CDS_SEC"1"
MATERIAL"EMPTY"
TOLERANCE"20%"
VALUE"470UF"
PART_NUMBER"CH747LM8825"
VOLTAGE"2.5V"
PACK_TYPE"SMLF"
CDS_LIB"pure_quanta";
"A"
$PN"1"20;
"B"
$PN"2"51;
%"VCC_CORE"
"1","(7725,3400)","0","pure_quanta_power","I69";
;
HDL_POWER"PVDDIO_P1"
CDS_LIB"pure_quanta_power";
"A"20;
%"Q_CAP"
"1","(7100,4600)","0","pure_quanta","I70";
;
LOCATION"PC451"
$SEC"1"
CDS_SEC"1"
MATERIAL"X7R"
TOLERANCE"10%"
VALUE"100NF"
PART_NUMBER"CH4106K1B01"
VOLTAGE"50V"
PACK_TYPE"C0402"
CDS_LIB"pure_quanta";
"B"
$PN"2"17;
"A"
$PN"1"19;
%"VCC_CORE"
"1","(5650,6075)","0","pure_quanta_power","I71";
;
HDL_POWER"P12V_STBY"
CDS_LIB"pure_quanta_power";
"A"11;
%"Q_CAP"
"1","(7425,4600)","0","pure_quanta","I72";
;
LOCATION"PC456_1"
$SEC"1"
CDS_SEC"1"
MATERIAL"X6S"
TOLERANCE"20%"
VALUE"22UF"
PART_NUMBER"TMP_QCH622KMEA01"
VOLTAGE"4V"
PACK_TYPE"0805"
CDS_LIB"pure_quanta";
"B"
$PN"2"17;
"A"
$PN"1"19;
%"Q_CAP"
"1","(7875,4600)","0","pure_quanta","I73";
;
LOCATION"PC459_1"
$SEC"1"
CDS_SEC"1"
MATERIAL"X6S"
TOLERANCE"20%"
VALUE"22UF"
VOLTAGE"4V"
PACK_TYPE"0805"
CDS_LIB"pure_quanta"
PART_NUMBER"TMP_QCH622KMEA01";
"B"
$PN"2"17;
"A"
$PN"1"19;
%"Q_INDUCTOR"
"1","(5375,5975)","0","pure_quanta","I74";
;
LOCATION"PL49"
$SEC"1"
CDS_SEC"1"
MATERIAL"IND"
VALUE"50NH/86A"
PART_NUMBER"CVA50^0MZ09"
PACK_TYPE"SMLF"
NEEDS_NO_SIZE"TRUE"
CDS_LIB"pure_quanta";
"1"
$PN"1"49;
"2"
$PN"2"11;
%"UNIVERSAL_GND"
"1","(8175,4250)","0","pure_quanta_power","I75";
;
CDS_LIB"pure_quanta_power"
HDL_POWER"GND";
"A"17;
%"VCC_CORE"
"1","(8175,4900)","0","pure_quanta_power","I76";
;
HDL_POWER"PVDDIO_P1"
CDS_LIB"pure_quanta_power";
"A"19;
%"UNIVERSAL_GND"
"1","(7825,1500)","0","pure_quanta_power","I80";
;
CDS_LIB"pure_quanta_power"
HDL_POWER"GND";
"A"22;
%"Q_CAP"
"1","(4650,5725)","0","pure_quanta","I85";
;
LOCATION"PC448_1"
$SEC"1"
CDS_SEC"1"
PART_NUMBER"CH6104KEA00"
MATERIAL"X6S"
TOLERANCE"10%"
VALUE"10UF"
VOLTAGE"25V"
PACK_TYPE"C0805"
CDS_LIB"pure_quanta";
"B"
$PN"2"48;
"A"
$PN"1"49;
%"Q_CAP"
"1","(5175,2975)","0","pure_quanta","I86";
;
LOCATION"PC449_2"
$SEC"1"
CDS_SEC"1"
PART_NUMBER"CH6104KEA00"
MATERIAL"X6S"
TOLERANCE"10%"
VALUE"10UF"
VOLTAGE"25V"
PACK_TYPE"C0805"
CDS_LIB"pure_quanta";
"B"
$PN"2"39;
"A"
$PN"1"55;
END.
